(kicad_pcb
	(version 20241229)
	(generator "pcbnew")
	(generator_version "9.0")
	(general
		(thickness 1.294)
		(legacy_teardrops no)
	)
	(paper "A3")
	(title_block
		(title "Kintex 410T devboard")
		(date "2024-04-03")
		(rev "1.1.2")
		(comment 9 "footprints 539-544 of 975")
	)
	(layers
		(0 "F.Cu" mixed)
		(4 "In1.Cu" power)
		(6 "In2.Cu" power)
		(8 "In3.Cu" mixed)
		(10 "In4.Cu" power)
		(12 "In5.Cu" mixed)
		(14 "In6.Cu" power)
		(16 "In7.Cu" mixed)
		(18 "In8.Cu" power)
		(2 "B.Cu" mixed)
		(9 "F.Adhes" user "F.Adhesive")
		(11 "B.Adhes" user "B.Adhesive")
		(13 "F.Paste" user)
		(15 "B.Paste" user)
		(5 "F.SilkS" user "F.Silkscreen")
		(7 "B.SilkS" user "B.Silkscreen")
		(1 "F.Mask" user)
		(3 "B.Mask" user)
		(17 "Dwgs.User" user "User.Drawings")
		(19 "Cmts.User" user "User.Comments")
		(21 "Eco1.User" user "User.Eco1")
		(23 "Eco2.User" user "User.Eco2")
		(25 "Edge.Cuts" user)
		(27 "Margin" user)
		(31 "F.CrtYd" user "F.Courtyard")
		(29 "B.CrtYd" user "B.Courtyard")
		(35 "F.Fab" user)
		(33 "B.Fab" user)
	)
	(footprint "antmicro-footprints:R_0402_1005Metric"
		(layer "B.Cu")
		(at 188.100001 84.800001 90)
		(descr "Resistor SMD 0402")
		(tags "resistor SMD 0402")
		(property "Reference" "R135"
			(at -0.725 0.4 270)
			(layer "B.SilkS")
			(effects
				(font
					(size 0.7 0.7)
					(thickness 0.15)
				)
				(justify left bottom mirror)
			)
		)
		(property "Value" "R_100R_0402"
			(at 0 -1.4 270)
			(layer "B.Fab")
			(effects
				(font
					(size 0.7 0.7)
					(thickness 0.15)
				)
				(justify left bottom mirror)
			)
		)
		(property "Description" "SMD Chip Resistor, 100 ohm, ± 1%, 62.5 mW, 0402 [1005 Metric], Thick Film, General Purpose"
			(at 0 0 90)
			(layer "F.Fab")
			(hide yes)
			(effects
				(font
					(size 1.27 1.27)
					(thickness 0.15)
				)
			)
		)
		(property "Author" "Antmicro"
			(at 272.900002 -103.3 0)
			(layer "B.Fab")
			(hide yes)
			(effects
				(font
					(size 1 1)
					(thickness 0.15)
				)
				(justify mirror)
			)
		)
		(property "License" "Apache-2.0"
			(at 272.900002 -103.3 0)
			(layer "B.Fab")
			(hide yes)
			(effects
				(font
					(size 1 1)
					(thickness 0.15)
				)
				(justify mirror)
			)
		)
		(property "MPN" "CR0402-FX-1000GLF"
			(at 272.900002 -103.3 0)
			(layer "B.Fab")
			(hide yes)
			(effects
				(font
					(size 1 1)
					(thickness 0.15)
				)
				(justify mirror)
			)
		)
		(property "Manufacturer" "Bourns"
			(at 272.900002 -103.3 0)
			(layer "B.Fab")
			(hide yes)
			(effects
				(font
					(size 1 1)
					(thickness 0.15)
				)
				(justify mirror)
			)
		)
		(property "Tolerance" "1%"
			(at 272.900002 -103.3 0)
			(layer "B.Fab")
			(hide yes)
			(effects
				(font
					(size 1 1)
					(thickness 0.15)
				)
				(justify mirror)
			)
		)
		(property "Val" "100R"
			(at 272.900002 -103.3 0)
			(layer "B.Fab")
			(hide yes)
			(effects
				(font
					(size 1 1)
					(thickness 0.15)
				)
				(justify mirror)
			)
		)
		(sheetname "User GPIO + LED + button + DIP switch")
		(sheetfile "user-gpio.kicad_sch")
		(attr smd)
		(fp_rect
			(start -0.925 0.47)
			(end 0.925 -0.47)
			(stroke
				(width 0.05)
				(type default)
			)
			(fill no)
			(layer "B.CrtYd")
		)
		(fp_rect
			(start -0.5 0.25)
			(end 0.5 -0.25)
			(stroke
				(width 0.15)
				(type solid)
			)
			(fill no)
			(layer "B.Fab")
		)
		(pad "1" smd roundrect
			(at -0.48 0 90)
			(size 0.59 0.64)
			(layers "B.Cu" "B.Mask" "B.Paste")
			(roundrect_rratio 0.25)
			(net 825 "/User GPIO + LED + button + DIP switch/CW_20PIN_MISO")
			(pintype "passive")
		)
		(pad "2" smd roundrect
			(at 0.48 0 90)
			(size 0.59 0.64)
			(layers "B.Cu" "B.Mask" "B.Paste")
			(roundrect_rratio 0.25)
			(net 475 "/FPGA Bank 12 & 13/CW_HEADER.MISO")
			(pintype "passive")
		)
	)
	(footprint "antmicro-footprints:R_0603_1608Metric"
		(layer "B.Cu")
		(at 256.801 152.5)
		(descr "Resistor SMD 0603")
		(tags "resistor SMD 0603")
		(property "Reference" "R263"
			(at 1.374 -0.55 180)
			(layer "B.SilkS")
			(effects
				(font
					(size 0.7 0.7)
					(thickness 0.15)
				)
				(justify left bottom mirror)
			)
		)
		(property "Value" "R_220R_0603"
			(at 0 -1.6 180)
			(layer "B.Fab")
			(effects
				(font
					(size 0.7 0.7)
					(thickness 0.15)
				)
				(justify left bottom mirror)
			)
		)
		(property "Description" "SMD Chip Resistor, 220 ohm, ± 1%, 100 mW, 0603 [1608 Metric], Thick Film, General Purpose"
			(at 0 0 0)
			(layer "F.Fab")
			(hide yes)
			(effects
				(font
					(size 1.27 1.27)
					(thickness 0.15)
				)
			)
		)
		(property "Author" "Antmicro"
			(at 0 0 0)
			(layer "B.Fab")
			(hide yes)
			(effects
				(font
					(size 1 1)
					(thickness 0.15)
				)
				(justify mirror)
			)
		)
		(property "License" "Apache-2.0"
			(at 0 0 0)
			(layer "B.Fab")
			(hide yes)
			(effects
				(font
					(size 1 1)
					(thickness 0.15)
				)
				(justify mirror)
			)
		)
		(property "MPN" "CR0603-FX-2200ELF"
			(at 0 0 0)
			(layer "B.Fab")
			(hide yes)
			(effects
				(font
					(size 1 1)
					(thickness 0.15)
				)
				(justify mirror)
			)
		)
		(property "Manufacturer" "Bourns"
			(at 0 0 0)
			(layer "B.Fab")
			(hide yes)
			(effects
				(font
					(size 1 1)
					(thickness 0.15)
				)
				(justify mirror)
			)
		)
		(property "Tolerance" "1%"
			(at 0 0 0)
			(layer "B.Fab")
			(hide yes)
			(effects
				(font
					(size 1 1)
					(thickness 0.15)
				)
				(justify mirror)
			)
		)
		(property "Val" "220R"
			(at 0 0 0)
			(layer "B.Fab")
			(hide yes)
			(effects
				(font
					(size 1 1)
					(thickness 0.15)
				)
				(justify mirror)
			)
		)
		(sheetname "HDMI + Ethernet")
		(sheetfile "hdmi-ethernet.kicad_sch")
		(attr smd)
		(fp_line
			(start -0.15 -0.4)
			(end 0.15 -0.4)
			(stroke
				(width 0.15)
				(type solid)
			)
			(layer "B.SilkS")
		)
		(fp_line
			(start -0.15 0.4)
			(end 0.15 0.4)
			(stroke
				(width 0.15)
				(type solid)
			)
			(layer "B.SilkS")
		)
		(fp_rect
			(start -1.25 0.65)
			(end 1.25 -0.65)
			(stroke
				(width 0.05)
				(type solid)
			)
			(fill no)
			(layer "B.CrtYd")
		)
		(fp_rect
			(start -0.8 0.4)
			(end 0.8 -0.4)
			(stroke
				(width 0.15)
				(type solid)
			)
			(fill no)
			(layer "B.Fab")
		)
		(pad "1" smd roundrect
			(at -0.7 0)
			(size 0.8 1)
			(layers "B.Cu" "B.Mask" "B.Paste")
			(roundrect_rratio 0.2)
			(net 852 "/HDMI + Ethernet/GBE_LED_SPD+")
			(pintype "passive")
		)
		(pad "2" smd roundrect
			(at 0.7 0)
			(size 0.8 1)
			(layers "B.Cu" "B.Mask" "B.Paste")
			(roundrect_rratio 0.2)
			(net 24 "+3V3")
			(pintype "passive")
		)
	)
	(footprint "antmicro-footprints:C_0402_1005Metric"
		(layer "B.Cu")
		(at 167.1 188.6 180)
		(descr "Capacitor SMD 0402")
		(tags "capacitor SMD 0402")
		(property "Reference" "C338"
			(at -1.125 0.5 0)
			(layer "B.SilkS")
			(effects
				(font
					(size 0.7 0.7)
					(thickness 0.15)
				)
				(justify left bottom mirror)
			)
		)
		(property "Value" "C_100n_0402"
			(at 0 -1.4 0)
			(layer "B.Fab")
			(effects
				(font
					(size 0.7 0.7)
					(thickness 0.15)
				)
				(justify left bottom mirror)
			)
		)
		(property "Description" "SMD Multilayer Ceramic Capacitor, 0.1 µF, 50 V, 0402 [1005 Metric], ± 10%, X5R, GRM Series"
			(at 0 0 180)
			(layer "F.Fab")
			(hide yes)
			(effects
				(font
					(size 1.27 1.27)
					(thickness 0.15)
				)
			)
		)
		(property "Author" "Antmicro"
			(at 334.2 377.2 0)
			(layer "B.Fab")
			(hide yes)
			(effects
				(font
					(size 1 1)
					(thickness 0.15)
				)
				(justify mirror)
			)
		)
		(property "Dielectric" "X5R"
			(at 334.2 377.2 0)
			(layer "B.Fab")
			(hide yes)
			(effects
				(font
					(size 1 1)
					(thickness 0.15)
				)
				(justify mirror)
			)
		)
		(property "License" "Apache-2.0"
			(at 334.2 377.2 0)
			(layer "B.Fab")
			(hide yes)
			(effects
				(font
					(size 1 1)
					(thickness 0.15)
				)
				(justify mirror)
			)
		)
		(property "MPN" "GRM155R61H104KE14D"
			(at 334.2 377.2 0)
			(layer "B.Fab")
			(hide yes)
			(effects
				(font
					(size 1 1)
					(thickness 0.15)
				)
				(justify mirror)
			)
		)
		(property "Manufacturer" "Murata"
			(at 334.2 377.2 0)
			(layer "B.Fab")
			(hide yes)
			(effects
				(font
					(size 1 1)
					(thickness 0.15)
				)
				(justify mirror)
			)
		)
		(property "Val" "100n"
			(at 334.2 377.2 0)
			(layer "B.Fab")
			(hide yes)
			(effects
				(font
					(size 1 1)
					(thickness 0.15)
				)
				(justify mirror)
			)
		)
		(property "Voltage" "50V"
			(at 334.2 377.2 0)
			(layer "B.Fab")
			(hide yes)
			(effects
				(font
					(size 1 1)
					(thickness 0.15)
				)
				(justify mirror)
			)
		)
		(sheetname "DC-DC Converters")
		(sheetfile "dc-dc.kicad_sch")
		(attr smd)
		(fp_rect
			(start -0.925 0.47)
			(end 0.925 -0.47)
			(stroke
				(width 0.05)
				(type default)
			)
			(fill no)
			(layer "B.CrtYd")
		)
		(fp_line
			(start 0.504 0.25)
			(end 0.504 -0.248)
			(stroke
				(width 0.15)
				(type solid)
			)
			(layer "B.Fab")
		)
		(fp_line
			(start 0.504 -0.248)
			(end -0.494 -0.248)
			(stroke
				(width 0.15)
				(type solid)
			)
			(layer "B.Fab")
		)
		(fp_line
			(start -0.494 0.25)
			(end 0.504 0.25)
			(stroke
				(width 0.15)
				(type solid)
			)
			(layer "B.Fab")
		)
		(fp_line
			(start -0.494 -0.248)
			(end -0.494 0.25)
			(stroke
				(width 0.15)
				(type solid)
			)
			(layer "B.Fab")
		)
		(pad "1" smd roundrect
			(at -0.48 0 180)
			(size 0.59 0.64)
			(layers "B.Cu" "B.Mask" "B.Paste")
			(roundrect_rratio 0.25)
			(net 1 "GND")
			(pintype "passive")
		)
		(pad "2" smd roundrect
			(at 0.48 0 180)
			(size 0.59 0.64)
			(layers "B.Cu" "B.Mask" "B.Paste")
			(roundrect_rratio 0.25)
			(net 37 "+3V3_AON")
			(pintype "passive")
		)
	)
	(footprint "antmicro-footprints:C_0201"
		(layer "B.Cu")
		(at 203 129.65)
		(descr "Capacitor SMD 0201")
		(tags "capacitor SMD 0201")
		(property "Reference" "C48"
			(at 26.825 -28.625 0)
			(layer "B.SilkS")
			(effects
				(font
					(size 0.7 0.7)
					(thickness 0.15)
				)
				(justify right bottom mirror)
			)
		)
		(property "Value" "C_4u7_0201"
			(at 0 -1.4 0)
			(layer "B.Fab")
			(effects
				(font
					(size 0.7 0.7)
					(thickness 0.15)
				)
				(justify right bottom mirror)
			)
		)
		(property "Description" "SMD Multilayer Ceramic Capacitor, 4.7 µF, 6.3 V, 0201 [0603 Metric], ± 20%, X5R, GRM Series"
			(at 0 0 0)
			(layer "F.Fab")
			(hide yes)
			(effects
				(font
					(size 1.27 1.27)
					(thickness 0.15)
				)
			)
		)
		(property "Author" "Antmicro"
			(at 0 0 0)
			(layer "B.Fab")
			(hide yes)
			(effects
				(font
					(size 1 1)
					(thickness 0.15)
				)
				(justify mirror)
			)
		)
		(property "Dielectric" ""
			(at 0 0 0)
			(layer "B.Fab")
			(hide yes)
			(effects
				(font
					(size 1 1)
					(thickness 0.15)
				)
				(justify mirror)
			)
		)
		(property "License" "Apache-2.0"
			(at 0 0 0)
			(layer "B.Fab")
			(hide yes)
			(effects
				(font
					(size 1 1)
					(thickness 0.15)
				)
				(justify mirror)
			)
		)
		(property "MPN" "GRM035R60J475ME15D"
			(at 0 0 0)
			(layer "B.Fab")
			(hide yes)
			(effects
				(font
					(size 1 1)
					(thickness 0.15)
				)
				(justify mirror)
			)
		)
		(property "Manufacturer" "Murata"
			(at 0 0 0)
			(layer "B.Fab")
			(hide yes)
			(effects
				(font
					(size 1 1)
					(thickness 0.15)
				)
				(justify mirror)
			)
		)
		(property "Val" "4u7"
			(at 0 0 0)
			(layer "B.Fab")
			(hide yes)
			(effects
				(font
					(size 1 1)
					(thickness 0.15)
				)
				(justify mirror)
			)
		)
		(property "Voltage" ""
			(at 0 0 0)
			(layer "B.Fab")
			(hide yes)
			(effects
				(font
					(size 1 1)
					(thickness 0.15)
				)
				(justify mirror)
			)
		)
		(sheetname "FPGA supply")
		(sheetfile "fpga-supply.kicad_sch")
		(attr smd)
		(fp_rect
			(start -0.7 0.35)
			(end 0.7 -0.35)
			(stroke
				(width 0.05)
				(type default)
			)
			(fill no)
			(layer "B.CrtYd")
		)
		(fp_rect
			(start 0.3 -0.15)
			(end -0.301 0.149)
			(stroke
				(width 0.15)
				(type solid)
			)
			(fill no)
			(layer "B.Fab")
		)
		(pad "" smd roundrect
			(at -0.349 0.002)
			(size 0.318 0.36)
			(layers "B.Paste")
			(roundrect_rratio 0.25)
		)
		(pad "" smd roundrect
			(at 0.341 0.002)
			(size 0.318 0.36)
			(layers "B.Paste")
			(roundrect_rratio 0.25)
		)
		(pad "1" smd roundrect
			(at -0.321 0.002)
			(size 0.46 0.4)
			(layers "B.Cu" "B.Mask")
			(roundrect_rratio 0.25)
			(net 1 "GND")
			(pintype "passive")
		)
		(pad "2" smd roundrect
			(at 0.32 0.002)
			(size 0.46 0.4)
			(layers "B.Cu" "B.Mask")
			(roundrect_rratio 0.25)
			(net 650 "+1V0")
			(pintype "passive")
		)
	)
	(footprint "antmicro-footprints:R_0402_1005Metric"
		(layer "B.Cu")
		(at 266.8 88.6 -90)
		(descr "Resistor SMD 0402")
		(tags "resistor SMD 0402")
		(property "Reference" "R148"
			(at -1.4 -1.325 90)
			(layer "B.SilkS")
			(effects
				(font
					(size 0.7 0.7)
					(thickness 0.15)
				)
				(justify left bottom mirror)
			)
		)
		(property "Value" "R_10k_0402"
			(at 0 -1.4 90)
			(layer "B.Fab")
			(effects
				(font
					(size 0.7 0.7)
					(thickness 0.15)
				)
				(justify left bottom mirror)
			)
		)
		(property "Description" "SMD Chip Resistor, 10 kohm, ± 1%, 62.5 mW, 0402 [1005 Metric], Thick Film, General Purpose"
			(at 0 0 270)
			(layer "F.Fab")
			(hide yes)
			(effects
				(font
					(size 1.27 1.27)
					(thickness 0.15)
				)
			)
		)
		(property "Author" "Antmicro"
			(at 178.2 355.4 0)
			(layer "B.Fab")
			(hide yes)
			(effects
				(font
					(size 1 1)
					(thickness 0.15)
				)
				(justify mirror)
			)
		)
		(property "License" "Apache-2.0"
			(at 178.2 355.4 0)
			(layer "B.Fab")
			(hide yes)
			(effects
				(font
					(size 1 1)
					(thickness 0.15)
				)
				(justify mirror)
			)
		)
		(property "MPN" "CR0402-FX-1002GLF"
			(at 178.2 355.4 0)
			(layer "B.Fab")
			(hide yes)
			(effects
				(font
					(size 1 1)
					(thickness 0.15)
				)
				(justify mirror)
			)
		)
		(property "Manufacturer" "Bourns"
			(at 178.2 355.4 0)
			(layer "B.Fab")
			(hide yes)
			(effects
				(font
					(size 1 1)
					(thickness 0.15)
				)
				(justify mirror)
			)
		)
		(property "Tolerance" "1%"
			(at 178.2 355.4 0)
			(layer "B.Fab")
			(hide yes)
			(effects
				(font
					(size 1 1)
					(thickness 0.15)
				)
				(justify mirror)
			)
		)
		(property "Val" "10k"
			(at 178.2 355.4 0)
			(layer "B.Fab")
			(hide yes)
			(effects
				(font
					(size 1 1)
					(thickness 0.15)
				)
				(justify mirror)
			)
		)
		(sheetname "User GPIO + LED + button + DIP switch")
		(sheetfile "user-gpio.kicad_sch")
		(attr smd)
		(fp_rect
			(start -0.925 0.47)
			(end 0.925 -0.47)
			(stroke
				(width 0.05)
				(type default)
			)
			(fill no)
			(layer "B.CrtYd")
		)
		(fp_rect
			(start -0.5 0.25)
			(end 0.5 -0.25)
			(stroke
				(width 0.15)
				(type solid)
			)
			(fill no)
			(layer "B.Fab")
		)
		(pad "1" smd roundrect
			(at -0.48 0 270)
			(size 0.59 0.64)
			(layers "B.Cu" "B.Mask" "B.Paste")
			(roundrect_rratio 0.25)
			(net 26 "+1V8")
			(pintype "passive")
		)
		(pad "2" smd roundrect
			(at 0.48 0 270)
			(size 0.59 0.64)
			(layers "B.Cu" "B.Mask" "B.Paste")
			(roundrect_rratio 0.25)
			(net 1233 "/USER_IO.BUTTON2")
			(pintype "passive")
		)
	)
	(footprint "antmicro-footprints:R_0402_1005Metric"
		(layer "B.Cu")
		(at 261.5 79)
		(descr "Resistor SMD 0402")
		(tags "resistor SMD 0402")
		(property "Reference" "R130"
			(at 1.45 1.25 180)
			(layer "B.SilkS")
			(effects
				(font
					(size 0.7 0.7)
					(thickness 0.15)
				)
				(justify left bottom mirror)
			)
		)
		(property "Value" "R_1k_0402"
			(at 0 -1.4 180)
			(layer "B.Fab")
			(effects
				(font
					(size 0.7 0.7)
					(thickness 0.15)
				)
				(justify left bottom mirror)
			)
		)
		(property "Description" "SMD Chip Resistor, 1 kohm, ± 1%, 63 mW, 0402 [1005 Metric], Thick Film, General Purpose"
			(at 0 0 0)
			(layer "F.Fab")
			(hide yes)
			(effects
				(font
					(size 1.27 1.27)
					(thickness 0.15)
				)
			)
		)
		(property "Author" "Antmicro"
			(at 0 0 0)
			(layer "B.Fab")
			(hide yes)
			(effects
				(font
					(size 1 1)
					(thickness 0.15)
				)
				(justify mirror)
			)
		)
		(property "License" "Apache-2.0"
			(at 0 0 0)
			(layer "B.Fab")
			(hide yes)
			(effects
				(font
					(size 1 1)
					(thickness 0.15)
				)
				(justify mirror)
			)
		)
		(property "MPN" "CR0402-FX-1001GLF"
			(at 0 0 0)
			(layer "B.Fab")
			(hide yes)
			(effects
				(font
					(size 1 1)
					(thickness 0.15)
				)
				(justify mirror)
			)
		)
		(property "Manufacturer" "Bourns"
			(at 0 0 0)
			(layer "B.Fab")
			(hide yes)
			(effects
				(font
					(size 1 1)
					(thickness 0.15)
				)
				(justify mirror)
			)
		)
		(property "Tolerance" "1%"
			(at 0 0 0)
			(layer "B.Fab")
			(hide yes)
			(effects
				(font
					(size 1 1)
					(thickness 0.15)
				)
				(justify mirror)
			)
		)
		(property "Val" "1k"
			(at 0 0 0)
			(layer "B.Fab")
			(hide yes)
			(effects
				(font
					(size 1 1)
					(thickness 0.15)
				)
				(justify mirror)
			)
		)
		(sheetname "User GPIO + LED + button + DIP switch")
		(sheetfile "user-gpio.kicad_sch")
		(attr smd)
		(fp_rect
			(start -0.925 0.47)
			(end 0.925 -0.47)
			(stroke
				(width 0.05)
				(type default)
			)
			(fill no)
			(layer "B.CrtYd")
		)
		(fp_rect
			(start -0.5 0.25)
			(end 0.5 -0.25)
			(stroke
				(width 0.15)
				(type solid)
			)
			(fill no)
			(layer "B.Fab")
		)
		(pad "1" smd roundrect
			(at -0.48 0)
			(size 0.59 0.64)
			(layers "B.Cu" "B.Mask" "B.Paste")
			(roundrect_rratio 0.25)
			(net 24 "+3V3")
			(pintype "passive")
		)
		(pad "2" smd roundrect
			(at 0.48 0)
			(size 0.59 0.64)
			(layers "B.Cu" "B.Mask" "B.Paste")
			(roundrect_rratio 0.25)
			(net 773 "Net-(D24-A)")
			(pintype "passive")
		)
	)
)
